FILE_TYPE = CONNECTIVITY;
{Allegro Design Entry HDL 16.6-p007 (v16-6-112F) 10/10/2012}
"PAGE_NUMBER" = 72;
0"NC";
1"PVDDQ_GHJ\g";
2"PVDDQ_KLM\g";
3"PVCCIO_CPU1\g";
4"PVCCIO_CPU1\g";
5"PVSA_CPU1\g";
6"GND\g";
7"PVCCMCP_CPU1\g";
8"PVCCIOMCP_CPU1\g";
9"PVPP_GHJ\g";
10"P1V8_MCP_CPU1\g";
11"P3V3_STBY\g";
%"PVDDQ_GHJ"
"1","(-7325,4250)","0","mstr_symbols","I14";
;
HDL_POWER"PVDDQ_GHJ"
BODY_TYPE"PLUMBING"
CDS_LIB"mstr_symbols"
VOLTAGE"1.2V";
"G\NAC"1;
%"PVDDQ_KLM"
"1","(-5050,4250)","0","mstr_symbols","I15";
;
HDL_POWER"PVDDQ_KLM"
BODY_TYPE"PLUMBING"
CDS_LIB"mstr_symbols"
VOLTAGE"1.2V";
"G\NAC"2;
%"PVCCIO_CPU1"
"1","(-3850,4850)","0","mstr_symbols","I17";
;
HDL_POWER"PVCCIO_CPU1"
BODY_TYPE"PLUMBING"
CDS_LIB"mstr_symbols"
VOLTAGE"1.1V";
"G\NAC"3;
%"PVCCIO_CPU1"
"1","(-900,1050)","0","mstr_symbols","I18";
;
HDL_POWER"PVCCIO_CPU1"
BODY_TYPE"PLUMBING"
CDS_LIB"mstr_symbols"
VOLTAGE"1.1V";
"G\NAC"4;
%"PVSA_CPU1"
"1","(-1600,4825)","0","mstr_symbols","I22";
;
HDL_POWER"PVSA_CPU1"
BODY_TYPE"PLUMBING"
CDS_LIB"mstr_symbols"
VOLTAGE"1.1V";
"G\NAC"5;
%"GND"
"1","(-525,775)","0","mstr_symbols","I23";
;
HDL_POWER"GND"
BODY_TYPE"PLUMBING"
SIZE"1B"
CDS_LIB"mstr_symbols"
VOLTAGE"0.0V";
"A\NAC"6;
%"CAP"
"1","(-525,1075)","0","mstr_discrete","I25";
;
ROOM"CPU1"
CDS_LOCATION"C3D3"
$SEC"1"
CDS_SEC"1"
CDS_LIB"mstr_discrete"
BOM_COST"PROC_SOCKET"
MATERIAL"X6S"
VOLTAGE"4V"
PACK_TYPE"0603LF"
TOLERANCE"20%"
VALUE"10UF"
PART_NUMBER"E15431-001"
LOCATION"C3D3";
"A"
$PN"1"10;
"B"
$PN"2"6;
%"VCC_CORE"
"1","(-1250,3300)","0","mstr_symbols","I28";
;
CDS_LIB"mstr_symbols"
HDL_POWER"PVCCMCP_CPU1";
"A"7;
%"VCC_CORE"
"1","(-1250,2575)","0","mstr_symbols","I29";
;
CDS_LIB"mstr_symbols"
VOLTAGE"+0.95V"
HDL_POWER"PVCCIOMCP_CPU1";
"A"8;
%"SKX_EXT_B"
"20","(-6200,2550)","0","chpset_lib","I32";
;
CDS_SEC"20"
CDS_LOCATION"U2D1"
SEC"20"
CDS_LIB"chpset_lib"
SEC_TYPE"BGA1"
PACK_TYPE"BGA1"
MATERIAL"IC"
PART_NUMBER"TBD"
LOCATION"U2D1";
"VCCD345<0>"
$PN"EF59"2;
"VCCD345<1>"
$PN"EF53"2;
"VCCD345<2>"
$PN"EF49"2;
"VCCD345<3>"
$PN"EC62"2;
"VCCD345<4>"
$PN"EC60"2;
"VCCD345<5>"
$PN"EC58"2;
"VCCD345<6>"
$PN"EC56"2;
"VCCD345<7>"
$PN"EC54"2;
"VCCD345<8>"
$PN"EC52"2;
"VCCD345<9>"
$PN"EC50"2;
"VCCD345<10>"
$PN"EC48"2;
"VCCD345<11>"
$PN"EC46"2;
"VCCD345<12>"
$PN"DU64"2;
"VCCD345<13>"
$PN"DU62"2;
"VCCD345<14>"
$PN"DU60"2;
"VCCD345<15>"
$PN"DU58"2;
"VCCD345<16>"
$PN"DU56"2;
"VCCD345<17>"
$PN"DU54"2;
"VCCD345<18>"
$PN"DU52"2;
"VCCD345<19>"
$PN"DU50"2;
"VCCD345<20>"
$PN"DU48"2;
"VCCD345<21>"
$PN"DU46"2;
"VCCD345<22>"
$PN"DL62"2;
"VCCD345<23>"
$PN"DL60"2;
"VCCD345<24>"
$PN"DL58"2;
"VCCD345<25>"
$PN"DL56"2;
"VCCD345<26>"
$PN"DL54"2;
"VCCD345<27>"
$PN"DL52"2;
"VCCD345<28>"
$PN"DL50"2;
"VCCD345<29>"
$PN"DL48"2;
"VCCD345<30>"
$PN"DL46"2;
"VCCD345<31>"
$PN"DJ64"2;
"VCCD345<32>"
$PN"DH63"2;
"VCCD345<33>"
$PN"DH61"2;
"VCCD345<34>"
$PN"DH59"2;
"VCCD345<35>"
$PN"DH57"2;
"VCCD345<36>"
$PN"DH55"2;
"VCCD345<37>"
$PN"DH53"2;
"VCCD345<38>"
$PN"DH51"2;
"VCCD345<39>"
$PN"DH49"2;
"VCCD345<40>"
$PN"DH47"2;
"VCCD345<41>"
$PN"DH45"2;
"VCCD345<42>"
$PN"DD45"2;
"VCCD345<43>"
$PN"DB63"2;
"VCCD345<44>"
$PN"DB61"2;
"VCCD345<45>"
$PN"DB59"2;
"VCCD345<46>"
$PN"DB57"2;
"VCCD345<47>"
$PN"DB55"2;
"VCCD345<48>"
$PN"DB53"2;
"VCCD345<49>"
$PN"EF45"2;
"VCCD345<50>"
$PN"EE44"2;
"VCCD012<0>"
$PN"B49"1;
"VCCD012<1>"
$PN"B53"1;
"VCCD012<2>"
$PN"B59"1;
"VCCD012<3>"
$PN"E46"1;
"VCCD012<4>"
$PN"E48"1;
"VCCD012<5>"
$PN"E50"1;
"VCCD012<6>"
$PN"E52"1;
"VCCD012<7>"
$PN"E54"1;
"VCCD012<8>"
$PN"E56"1;
"VCCD012<9>"
$PN"E58"1;
"VCCD012<10>"
$PN"E60"1;
"VCCD012<11>"
$PN"E62"1;
"VCCD012<12>"
$PN"E64"1;
"VCCD012<13>"
$PN"L46"1;
"VCCD012<14>"
$PN"L48"1;
"VCCD012<15>"
$PN"L50"1;
"VCCD012<16>"
$PN"L52"1;
"VCCD012<17>"
$PN"L54"1;
"VCCD012<18>"
$PN"L56"1;
"VCCD012<19>"
$PN"L58"1;
"VCCD012<20>"
$PN"L60"1;
"VCCD012<21>"
$PN"L62"1;
"VCCD012<22>"
$PN"N64"1;
"VCCD012<23>"
$PN"U46"1;
"VCCD012<24>"
$PN"U48"1;
"VCCD012<25>"
$PN"U50"1;
"VCCD012<26>"
$PN"U52"1;
"VCCD012<27>"
$PN"U54"1;
"VCCD012<28>"
$PN"U56"1;
"VCCD012<29>"
$PN"U58"1;
"VCCD012<30>"
$PN"U60"1;
"VCCD012<31>"
$PN"U62"1;
"VCCD012<32>"
$PN"W64"1;
"VCCD012<33>"
$PN"Y45"1;
"VCCD012<34>"
$PN"Y47"1;
"VCCD012<35>"
$PN"Y49"1;
"VCCD012<36>"
$PN"Y51"1;
"VCCD012<37>"
$PN"Y53"1;
"VCCD012<38>"
$PN"Y55"1;
"VCCD012<39>"
$PN"Y57"1;
"VCCD012<40>"
$PN"Y59"1;
"VCCD012<41>"
$PN"Y61"1;
"VCCD012<42>"
$PN"Y63"1;
"VCCD012<43>"
$PN"AD45"1;
"VCCD012<44>"
$PN"AF55"1;
"VCCD012<45>"
$PN"AF57"1;
"VCCD012<46>"
$PN"AF59"1;
"VCCD012<47>"
$PN"AF61"1;
"VCCD012<48>"
$PN"AF63"1;
"VCCD012<49>"
$PN"D45"1;
"VCCD012<50>"
$PN"C46"1;
"VCCD012<51>"
$PN"B47"1;
%"SKX_EXT_B"
"21","(-2700,2575)","0","chpset_lib","I33";
;
CDS_SEC"21"
CDS_LOCATION"U2D1"
SEC"21"
CDS_LIB"chpset_lib"
SEC_TYPE"BGA1"
PACK_TYPE"BGA1"
MATERIAL"IC"
PART_NUMBER"TBD"
LOCATION"U2D1";
"VCCSA<0>"
$PN"CJ66"5;
"VCCSA<1>"
$PN"CJ64"5;
"VCCSA<2>"
$PN"CH75"5;
"VCCSA<3>"
$PN"CH65"5;
"VCCSA<4>"
$PN"CG74"5;
"VCCSA<5>"
$PN"CG66"5;
"VCCSA<6>"
$PN"CG64"5;
"VCCSA<7>"
$PN"CF75"5;
"VCCSA<8>"
$PN"CF73"5;
"VCCSA<9>"
$PN"CF67"5;
"VCCSA<10>"
$PN"CF65"5;
"VCCSA<11>"
$PN"CE74"5;
"VCCSA<12>"
$PN"CE72"5;
"VCCSA<13>"
$PN"CE68"5;
"VCCSA<14>"
$PN"CE66"5;
"VCCSA<15>"
$PN"CE64"5;
"VCCSA<16>"
$PN"CD71"5;
"VCCSA<17>"
$PN"CD69"5;
"VCCSA<18>"
$PN"CD67"5;
"VCCSA<19>"
$PN"CD65"5;
"VCCSA<20>"
$PN"CC70"5;
"VCCSA<21>"
$PN"CC68"5;
"VCCSA<22>"
$PN"CC66"5;
"VCCSA<23>"
$PN"CB69"5;
"VCCSA<24>"
$PN"CB67"5;
"VCCSA<25>"
$PN"CB65"5;
"VCCIO<20>"
$PN"CM15"4;
"VCCIO<21>"
$PN"CL12"4;
"VCCIO<22>"
$PN"CK5"4;
"VCCIO<23>"
$PN"CV7"4;
"VCCIO<24>"
$PN"CH9"4;
"VCCIO<25>"
$PN"D7"4;
"VCCIO<26>"
$PN"CE18"4;
"VCCIO<27>"
$PN"CD9"4;
"VCCIO<28>"
$PN"CB17"4;
"VCCIO<29>"
$PN"CB13"4;
"VCCIO<30>"
$PN"BP25"3;
"VCCIO<31>"
$PN"BJ24"3;
"VCCIO<32>"
$PN"BF23"3;
"VCCIO<33>"
$PN"DA14"3;
"VCCIO<34>"
$PN"BB5"3;
"VCCIO<35>"
$PN"BA24"3;
"VCCIO<36>"
$PN"AY11"3;
"VCCIO<37>"
$PN"AW6"3;
"VCCIO<38>"
$PN"AT11"3;
"VCCIO<39>"
$PN"DD7"3;
"VCCIO<40>"
$PN"AN10"3;
"VCCIO<41>"
$PN"DF13"3;
"VCCIO<42>"
$PN"AH9"3;
"VCCIO<43>"
$PN"AC4"3;
"VCCIO<44>"
$PN"AC20"3;
"VCCIO<45>"
$PN"AA10"3;
"VCCIO<46>"
$PN"W6"3;
"VCCIO<47>"
$PN"W4"3;
"VCCIO<48>"
$PN"DF21"3;
"VCCIO<49>"
$PN"U14"3;
"VCCIO<50>"
$PN"T3"3;
"VCCIO<51>"
$PN"P5"3;
"VCCIO<52>"
$PN"M21"3;
"VCCIO<53>"
$PN"M11"3;
"VCCIO<54>"
$PN"DG8"3;
"VCCIO<55>"
$PN"DH7"3;
"VCCIO<56>"
$PN"L16"3;
"VCCIO<57>"
$PN"L14"3;
"VCCIO<58>"
$PN"J10"3;
"VCCIO<59>"
$PN"H13"3;
"VCCIO<60>"
$PN"DJ16"3;
"VCCIO<61>"
$PN"DM17"3;
"VCCIO<62>"
$PN"DN8"3;
"VCCIO<63>"
$PN"DP19"3;
"VCCIO<64>"
$PN"DR10"3;
"VCCIO<65>"
$PN"DR2"3;
"VCCIO<66>"
$PN"DU20"3;
"VCCIO<67>"
$PN"EA12"3;
"VCCIO<68>"
$PN"EB15"3;
"VCCIO<69>"
$PN"J2"3;
"VCCIO<70>"
$PN"K15"3;
"VCCIO<71>"
$PN"M7"3;
"VCCIO<72>"
$PN"M9"3;
"VCCIO<73>"
$PN"N18"3;
"VCCIO<74>"
$PN"W10"3;
"VCCIO<75>"
$PN"BC26"3;
"VCCIO<76>"
$PN"BB27"3;
"VCCIO<77>"
$PN"BA26"3;
"VCCIO<78>"
$PN"AY27"3;
"VCCIO<79>"
$PN"AW26"3;
"VCCIO<80>"
$PN"AV27"3;
"VCCIO<81>"
$PN"CF27"3;
"VCCIO<82>"
$PN"CD27"3;
"VCCIO<83>"
$PN"CC26"3;
"VCCIO<84>"
$PN"CJ28"3;
"VCCIO<85>"
$PN"CH27"3;
"VCCIO<86>"
$PN"BM27"3;
"VCCIO<87>"
$PN"BL26"3;
"VCCIO<88>"
$PN"BK27"3;
"VCCIO<89>"
$PN"BK25"3;
"VCCIO<90>"
$PN"BJ26"3;
"VCCIO<91>"
$PN"BH27"3;
"VCCIO<92>"
$PN"BH25"3;
"VCCIO<93>"
$PN"BG26"3;
"VCCIO<94>"
$PN"BF27"3;
"VCCIO<95>"
$PN"AE36"3;
"VCCIO<96>"
$PN"AD37"3;
"VCCIO<97>"
$PN"AC36"3;
"VCCIO<98>"
$PN"AF35"3;
"VCCIO<99>"
$PN"AD35"3;
"VCCIO<100>"
$PN"AE34"3;
"VCCIO<101>"
$PN"AG34"3;
"VCCIO<102>"
$PN"AM29"3;
"VCCIO<103>"
$PN"AL28"3;
"VCCIO<104>"
$PN"AR28"3;
"VCC33"
$PN"CY55"11;
"CD_VPP<0>"
$PN"B11"9;
"CD_VPP<1>"
$PN"A12"9;
"CD_VPP<2>"
$PN"A10"9;
"CD_VPP<3>"
$PN"A8"9;
"CD_VCC_CORE<0>"
$PN"BL14"7;
"CD_VCC_CORE<1>"
$PN"BK15"7;
"CD_VCC_CORE<2>"
$PN"BK13"7;
"CD_VCC_CORE<3>"
$PN"BJ14"7;
"CD_VCC_CORE<4>"
$PN"BJ12"7;
"CD_VCC_CORE<5>"
$PN"BH13"7;
"CD_VCC_CORE<6>"
$PN"BG14"7;
"CD_VCC_CORE<7>"
$PN"BG12"7;
"CD_VCC_CORE<8>"
$PN"BF13"7;
"CD_VCC_CORE<9>"
$PN"BF11"7;
"CD_VCC_CORE<10>"
$PN"BE14"7;
"CD_VCC_CORE<11>"
$PN"BE12"7;
"CD_VCC_CORE<12>"
$PN"BD13"7;
"CD_VCCP<0>"
$PN"BV15"8;
"CD_VCCP<1>"
$PN"BV13"8;
"CD_VCCP<2>"
$PN"BV11"8;
"CD_VCCP<3>"
$PN"BU14"8;
"CD_VCCP<4>"
$PN"BU12"8;
"CD_VCCP<5>"
$PN"BT15"8;
"CD_VCCP<6>"
$PN"BT13"8;
"CD_VCCP<7>"
$PN"BT11"8;
"CD_VCCP<8>"
$PN"BR14"8;
"CD_VCCP<9>"
$PN"BR12"8;
"CD_VCCP<10>"
$PN"BP15"8;
"CD_VCCP<11>"
$PN"BP13"8;
"CD_VCCP<12>"
$PN"BP11"8;
"CD_VCCP<13>"
$PN"BN14"8;
"CD_VCCP<14>"
$PN"BN12"8;
"CD_VCCP<15>"
$PN"BM11"8;
"CD_VCCIN<0>"
$PN"BT27"10;
"CD_VCCIN<1>"
$PN"BU26"10;
"CD_VCCIN<2>"
$PN"BV27"10;
"CD_VCCIN<3>"
$PN"BY27"10;
%"PVPP_GHJ"
"1","(-1425,1925)","0","mstr_symbols","I38";
;
HDL_POWER"PVPP_GHJ"
ROOM"PVPP_KLM_VR"
BODY_TYPE"PLUMBING"
CDS_LIB"mstr_symbols"
BOM_COST"PVPP_KLM_VR"
VOLTAGE"2.5V";
"G\NAC"9;
%"VCC_CORE"
"1","(-300,1525)","0","mstr_symbols","I39";
;
CDS_LIB"mstr_symbols"
VOLTAGE"1.8"
HDL_POWER"P1V8_MCP_CPU1";
"A"10;
%"P3V3_STBY"
"1","(-1150,1200)","0","mstr_symbols","I40";
;
HDL_POWER"P3V3_STBY"
BODY_TYPE"PLUMBING"
CDS_LIB"mstr_symbols"
SIZE"1B"
VOLTAGE"3.3V";
"G\NAC"11;
END.
